(kicad_pcb
	(version 20260206)
	(generator "pcbnew")
	(generator_version "10.0")
	(general
		(thickness 1.6)
		(legacy_teardrops no)
	)
	(paper "A4")
	(title_block
		(title "Bryce Canyon_Front Panel_16369-1_OCP.brd")
		(comment 1 "Bryce Canyon / footprints 38-41 of 154")
	)
	(layers
		(0 "F.Cu" signal "TOP")
		(4 "In1.Cu" signal "L2GND")
		(6 "In2.Cu" signal "L3VCC")
		(2 "B.Cu" signal "BOTTOM")
		(9 "F.Adhes" user "F.Adhesive")
		(11 "B.Adhes" user "B.Adhesive")
		(13 "F.Paste" user "Package Geometry/Pastemask Top")
		(15 "B.Paste" user "Package Geometry/Pastemask Bottom")
		(5 "F.SilkS" user "Ref Des/Silkscreen Top")
		(7 "B.SilkS" user "Ref Des/Silkscreen Bottom")
		(1 "F.Mask" user "Board Geometry/Soldermask Top")
		(3 "B.Mask" user "Board Geometry/Soldermask Bottom")
		(17 "Dwgs.User" user "User.Drawings")
		(19 "Cmts.User" user "User.Comments")
		(21 "Eco1.User" user "User.Eco1")
		(23 "Eco2.User" user "User.Eco2")
		(25 "Edge.Cuts" user "Board Geometry/Outline")
		(27 "Margin" user)
		(31 "F.CrtYd" user "Package Geometry/Place Bound Top")
		(29 "B.CrtYd" user "Package Geometry/Place Bound Bottom")
		(35 "F.Fab" user "Ref Des/Assembly Top")
		(33 "B.Fab" user "Ref Des/Assembly Bottom")
	)
	(footprint ""
		(layer "F.Cu")
		(at 48.90008 -59.99988 90)
		(property "Reference" "USB2"
			(at 0 0 90)
			(layer "F.SilkS")
			(hide yes)
			(effects
				(font
					(size 1.27 1.27)
				)
			)
		)
		(property "Value" "SKT-USB13-208-GP"
			(at -9.1821 -7.5692 90)
			(unlocked yes)
			(layer "F.Fab")
			(hide yes)
			(effects
				(font
					(size 1.016 1.016)
					(thickness 0.1524)
				)
			)
		)
		(property "Device Type" "SKT-USB13-148074-5"
			(at -9.1821 -9.0932 90)
			(unlocked yes)
			(layer "F.Fab")
			(hide yes)
			(effects
				(font
					(size 1.016 1.016)
					(thickness 0.1524)
				)
			)
		)
		(duplicate_pad_numbers_are_jumpers no)
		(fp_line
			(start 8.0137 -3.9497)
			(end 8.0137 3.9497)
			(stroke
				(width 0.1524)
				(type default)
			)
			(layer "F.SilkS")
		)
		(fp_line
			(start -8.0137 -3.9497)
			(end 8.0137 -3.9497)
			(stroke
				(width 0.1524)
				(type default)
			)
			(layer "F.SilkS")
		)
		(fp_line
			(start 8.0137 3.9497)
			(end -8.0137 3.9497)
			(stroke
				(width 0.1524)
				(type default)
			)
			(layer "F.SilkS")
		)
		(fp_line
			(start -8.0137 3.9497)
			(end -8.0137 -3.9497)
			(stroke
				(width 0.1524)
				(type default)
			)
			(layer "F.SilkS")
		)
		(fp_arc
			(start 4.854956 1.256792)
			(mid 8.078491 2.349096)
			(end 4.686808 2.064512)
			(stroke
				(width 0.3048)
				(type default)
			)
			(layer "F.SilkS")
		)
		(fp_arc
			(start -4.854956 1.256792)
			(mid -3.12974 1.318917)
			(end -4.686808 2.064512)
			(stroke
				(width 0.3048)
				(type default)
			)
			(layer "F.SilkS")
		)
		(fp_arc
			(start 4.686808 2.064512)
			(mid 3.129699 1.318908)
			(end 4.854956 1.256792)
			(stroke
				(width 0.3048)
				(type default)
			)
			(layer "F.SilkS")
		)
		(fp_arc
			(start -4.686808 2.064512)
			(mid -8.078519 2.349102)
			(end -4.854956 1.256792)
			(stroke
				(width 0.3048)
				(type default)
			)
			(layer "F.SilkS")
		)
		(fp_circle
			(center 6.400038 -1.999996)
			(end 6.400038 -0.285496)
			(stroke
				(width 0.3048)
				(type default)
			)
			(fill no)
			(layer "F.SilkS")
		)
		(fp_circle
			(center -6.400038 -1.999996)
			(end -6.400038 -0.285496)
			(stroke
				(width 0.3048)
				(type default)
			)
			(fill no)
			(layer "F.SilkS")
		)
		(fp_circle
			(center 3.50012 -0.999998)
			(end 3.50012 -0.110998)
			(stroke
				(width 0.3048)
				(type default)
			)
			(fill no)
			(layer "F.SilkS")
		)
		(fp_circle
			(center 0.999998 -0.999998)
			(end 0.999998 -0.110998)
			(stroke
				(width 0.3048)
				(type default)
			)
			(fill no)
			(layer "F.SilkS")
		)
		(fp_circle
			(center -0.999998 -0.999998)
			(end -0.999998 -0.110998)
			(stroke
				(width 0.3048)
				(type default)
			)
			(fill no)
			(layer "F.SilkS")
		)
		(fp_circle
			(center -3.50012 -0.999998)
			(end -3.50012 -0.110998)
			(stroke
				(width 0.3048)
				(type default)
			)
			(fill no)
			(layer "F.SilkS")
		)
		(fp_circle
			(center 1.999996 1.500124)
			(end 1.999996 2.389124)
			(stroke
				(width 0.3048)
				(type default)
			)
			(fill no)
			(layer "F.SilkS")
		)
		(fp_circle
			(center 0 1.500124)
			(end 0 2.389124)
			(stroke
				(width 0.3048)
				(type default)
			)
			(fill no)
			(layer "F.SilkS")
		)
		(fp_circle
			(center -1.999996 1.500124)
			(end -1.999996 2.389124)
			(stroke
				(width 0.3048)
				(type default)
			)
			(fill no)
			(layer "F.SilkS")
		)
		(fp_rect
			(start -7.4041 3.6957)
			(end 7.4041 -3.6957)
			(stroke
				(width 0)
				(type default)
			)
			(fill no)
			(layer "F.CrtYd")
		)
		(fp_poly
			(pts
				(xy -8.2677 4.2037) (xy -8.2677 -4.2037) (xy 8.2677 -4.2037) (xy 8.2677 -0.00635) (xy 7.4041 -0.00635)
				(xy 7.4041 -3.6957) (xy -7.4041 -3.6957) (xy -7.4041 3.6957) (xy 7.4041 3.6957) (xy 7.4041 0.00635)
				(xy 8.2677 0.00635) (xy 8.2677 4.2037)
			)
			(stroke
				(width 0)
				(type default)
			)
			(fill no)
			(layer "F.CrtYd")
		)
		(fp_rect
			(start -8.2677 4.2037)
			(end 8.2677 -4.2037)
			(stroke
				(width 0)
				(type default)
			)
			(fill no)
			(layer "F.Fab")
		)
		(pad "1" thru_hole circle
			(at 3.50012 -0.999998 90)
			(size 1.0668 1.0668)
			(drill 0.7112)
			(layers "*.Cu" "*.Mask")
			(remove_unused_layers no)
			(net "P5V_VBUS_B")
			(clearance 0.1778)
			(thermal_gap 0.1778)
		)
		(pad "2" thru_hole circle
			(at 0.999998 -0.999998 90)
			(size 1.0668 1.0668)
			(drill 0.7112)
			(layers "*.Cu" "*.Mask")
			(remove_unused_layers no)
			(net "DEBUG_USB_B_DN")
			(clearance 0.1778)
			(thermal_gap 0.1778)
		)
		(pad "3" thru_hole circle
			(at -0.999998 -0.999998 90)
			(size 1.0668 1.0668)
			(drill 0.7112)
			(layers "*.Cu" "*.Mask")
			(remove_unused_layers no)
			(net "DEBUG_USB_B_DP")
			(clearance 0.1778)
			(thermal_gap 0.1778)
		)
		(pad "4" thru_hole circle
			(at -3.50012 -0.999998 90)
			(size 1.0668 1.0668)
			(drill 0.7112)
			(layers "*.Cu" "*.Mask")
			(remove_unused_layers no)
			(net "GND")
			(clearance 0.1778)
			(thermal_gap 0.1778)
		)
		(pad "5" thru_hole circle
			(at -3.999992 1.500124 90)
			(size 1.0668 1.0668)
			(drill 0.7112)
			(layers "*.Cu" "*.Mask")
			(remove_unused_layers no)
			(net "I2C_DEBUG_B_SCL")
			(clearance 0.1778)
			(thermal_gap 0.1778)
		)
		(pad "6" thru_hole circle
			(at -1.999996 1.500124 90)
			(size 1.0668 1.0668)
			(drill 0.7112)
			(layers "*.Cu" "*.Mask")
			(remove_unused_layers no)
			(net "I2C_DEBUG_B_SDA")
			(clearance 0.1778)
			(thermal_gap 0.1778)
		)
		(pad "7" thru_hole circle
			(at 0 1.500124 90)
			(size 1.0668 1.0668)
			(drill 0.7112)
			(layers "*.Cu" "*.Mask")
			(remove_unused_layers no)
			(net "DEBUG_CARD_B_PRSNT")
			(clearance 0.1778)
			(thermal_gap 0.1778)
		)
		(pad "8" thru_hole circle
			(at 1.999996 1.500124 90)
			(size 1.0668 1.0668)
			(drill 0.7112)
			(layers "*.Cu" "*.Mask")
			(remove_unused_layers no)
			(net "UART_DEBUG_B_TX")
			(clearance 0.1778)
			(thermal_gap 0.1778)
		)
		(pad "9" thru_hole circle
			(at 3.999992 1.500124 90)
			(size 1.0668 1.0668)
			(drill 0.7112)
			(layers "*.Cu" "*.Mask")
			(remove_unused_layers no)
			(net "UART_DEBUG_B_RX")
			(clearance 0.1778)
			(thermal_gap 0.1778)
		)
		(pad "10" thru_hole circle
			(at 6.400038 -1.999996 90)
			(size 2.7178 2.7178)
			(drill 2.3114)
			(layers "*.Cu" "*.Mask")
			(remove_unused_layers no)
			(net "USB_CONN_B_GND")
			(clearance 0.1524)
			(thermal_gap 0.1524)
		)
		(pad "11" thru_hole circle
			(at -6.400038 -1.999996 90)
			(size 2.7178 2.7178)
			(drill 2.3114)
			(layers "*.Cu" "*.Mask")
			(remove_unused_layers no)
			(net "USB_CONN_B_GND")
			(clearance 0.1524)
			(thermal_gap 0.1524)
		)
		(pad "12" thru_hole circle
			(at 6.400038 1.999996 90)
			(size 2.7178 2.7178)
			(drill 2.3114)
			(layers "*.Cu" "*.Mask")
			(remove_unused_layers no)
			(net "USB_CONN_B_GND")
			(clearance 0.1524)
			(thermal_gap 0.1524)
		)
		(pad "13" thru_hole circle
			(at -6.400038 1.999996 90)
			(size 2.7178 2.7178)
			(drill 2.3114)
			(layers "*.Cu" "*.Mask")
			(remove_unused_layers no)
			(net "USB_CONN_B_GND")
			(clearance 0.1524)
			(thermal_gap 0.1524)
		)
		(zone
			(layer "F.Cu")
			(hatch none 0.5)
			(connect_pads
				(clearance 0)
			)
			(min_thickness 0.25)
			(keepout
				(tracks not_allowed)
				(vias allowed)
				(pads allowed)
				(copperpour not_allowed)
				(footprints allowed)
			)
			(placement
				(enabled no)
				(sheetname "")
			)
			(fill
				(thermal_gap 0.5)
				(thermal_bridge_width 0.5)
				(island_removal_mode 0)
			)
			(polygon
				(pts
					(xy 46.060106 -65.099946) (xy 51.740054 -65.099946) (xy 51.740054 -66.199766) (xy 46.060106 -66.199766)
				)
			)
		)
		(zone
			(layer "F.Cu")
			(hatch none 0.5)
			(connect_pads
				(clearance 0)
			)
			(min_thickness 0.25)
			(keepout
				(tracks not_allowed)
				(vias allowed)
				(pads allowed)
				(copperpour not_allowed)
				(footprints allowed)
			)
			(placement
				(enabled no)
				(sheetname "")
			)
			(fill
				(thermal_gap 0.5)
				(thermal_bridge_width 0.5)
				(island_removal_mode 0)
			)
			(polygon
				(pts
					(xy 46.060106 -53.799994) (xy 51.740054 -53.799994) (xy 51.740054 -54.899814) (xy 46.060106 -54.899814)
				)
			)
		)
		(zone
			(layer "F.Cu")
			(hatch none 0.5)
			(connect_pads
				(clearance 0)
			)
			(min_thickness 0.25)
			(keepout
				(tracks allowed)
				(vias not_allowed)
				(pads allowed)
				(copperpour not_allowed)
				(footprints allowed)
			)
			(placement
				(enabled no)
				(sheetname "")
			)
			(fill
				(thermal_gap 0.5)
				(thermal_bridge_width 0.5)
				(island_removal_mode 0)
			)
			(polygon
				(pts
					(xy 51.740054 -65.099946) (xy 51.740054 -66.199766) (xy 46.060106 -66.199766) (xy 46.060106 -65.099946)
				)
			)
		)
		(zone
			(layer "F.Cu")
			(hatch none 0.5)
			(connect_pads
				(clearance 0)
			)
			(min_thickness 0.25)
			(keepout
				(tracks allowed)
				(vias not_allowed)
				(pads allowed)
				(copperpour not_allowed)
				(footprints allowed)
			)
			(placement
				(enabled no)
				(sheetname "")
			)
			(fill
				(thermal_gap 0.5)
				(thermal_bridge_width 0.5)
				(island_removal_mode 0)
			)
			(polygon
				(pts
					(xy 51.740054 -53.799994) (xy 51.740054 -54.899814) (xy 46.060106 -54.899814) (xy 46.060106 -53.799994)
				)
			)
		)
	)
	(footprint ""
		(layer "F.Cu")
		(at 11.811 -48.66894 -90)
		(property "Reference" "R27"
			(at 0 0 270)
			(layer "F.SilkS")
			(hide yes)
			(effects
				(font
					(size 1.27 1.27)
				)
			)
		)
		(property "Value" "4K7R2F-GP"
			(at 0.064008 -4.679696 270)
			(unlocked yes)
			(layer "F.Fab")
			(hide yes)
			(effects
				(font
					(size 2.54 2.54)
					(thickness 0.381)
				)
			)
		)
		(property "Device Type" "R402H16"
			(at 0.064008 -6.203696 270)
			(unlocked yes)
			(layer "F.Fab")
			(hide yes)
			(effects
				(font
					(size 2.54 2.54)
					(thickness 0.381)
				)
			)
		)
		(duplicate_pad_numbers_are_jumpers no)
		(fp_line
			(start -0.508 -0.9398)
			(end -0.508 0.9398)
			(stroke
				(width 0.1524)
				(type default)
			)
			(layer "F.SilkS")
		)
		(fp_line
			(start 0.508 -0.9398)
			(end -0.508 -0.9398)
			(stroke
				(width 0.1524)
				(type default)
			)
			(layer "F.SilkS")
		)
		(fp_rect
			(start -0.508 0.9398)
			(end 0.508 -0.9398)
			(stroke
				(width 0)
				(type default)
			)
			(fill no)
			(layer "F.CrtYd")
		)
		(fp_rect
			(start -0.508 0.9398)
			(end 0.508 -0.9398)
			(stroke
				(width 0)
				(type default)
			)
			(fill no)
			(layer "F.Fab")
		)
		(pad "1" smd custom
			(at 0 -0.4445 270)
			(size 0.1397 0.1397)
			(layers "F.Cu" "F.Mask" "F.Paste")
			(net "P3V3_STBY_A")
			(options
				(clearance outline)
				(anchor circle)
			)
			(primitives
				(gr_poly
					(pts
						(arc
							(start -0.1778 -0.2794)
							(mid -0.249642 -0.249642)
							(end -0.2794 -0.1778)
						)
						(arc
							(start -0.2794 0.1778)
							(mid -0.249642 0.249642)
							(end -0.1778 0.2794)
						)
						(arc
							(start 0.1778 0.2794)
							(mid 0.249642 0.249642)
							(end 0.2794 0.1778)
						)
						(arc
							(start 0.2794 -0.1778)
							(mid 0.249642 -0.249642)
							(end 0.1778 -0.2794)
						)
					)
					(width 0)
					(fill yes)
				)
			)
		)
		(pad "2" smd custom
			(at 0 0.4445 270)
			(size 0.1397 0.1397)
			(layers "F.Cu" "F.Mask" "F.Paste")
			(net "TEMP_1_A0")
			(options
				(clearance outline)
				(anchor circle)
			)
			(primitives
				(gr_poly
					(pts
						(arc
							(start -0.1778 -0.2794)
							(mid -0.249642 -0.249642)
							(end -0.2794 -0.1778)
						)
						(arc
							(start -0.2794 0.1778)
							(mid -0.249642 0.249642)
							(end -0.1778 0.2794)
						)
						(arc
							(start 0.1778 0.2794)
							(mid 0.249642 0.249642)
							(end 0.2794 0.1778)
						)
						(arc
							(start 0.2794 -0.1778)
							(mid 0.249642 -0.249642)
							(end 0.1778 -0.2794)
						)
					)
					(width 0)
					(fill yes)
				)
			)
		)
	)
	(footprint ""
		(layer "F.Cu")
		(at 54.6862 -13.9446)
		(property "Reference" "R9"
			(at 0 0 0)
			(layer "F.SilkS")
			(hide yes)
			(effects
				(font
					(size 1.27 1.27)
				)
			)
		)
		(property "Value" "0R2J-2-GP"
			(at 0.064008 -4.679696 0)
			(unlocked yes)
			(layer "F.Fab")
			(hide yes)
			(effects
				(font
					(size 2.54 2.54)
					(thickness 0.381)
				)
			)
		)
		(property "Device Type" "R402H16"
			(at 0.064008 -6.203696 0)
			(unlocked yes)
			(layer "F.Fab")
			(hide yes)
			(effects
				(font
					(size 2.54 2.54)
					(thickness 0.381)
				)
			)
		)
		(duplicate_pad_numbers_are_jumpers no)
		(fp_line
			(start -0.508 -0.9398)
			(end -0.508 0.9398)
			(stroke
				(width 0.1524)
				(type default)
			)
			(layer "F.SilkS")
		)
		(fp_line
			(start 0.508 -0.9398)
			(end -0.508 -0.9398)
			(stroke
				(width 0.1524)
				(type default)
			)
			(layer "F.SilkS")
		)
		(fp_rect
			(start -0.508 0.9398)
			(end 0.508 -0.9398)
			(stroke
				(width 0)
				(type default)
			)
			(fill no)
			(layer "F.CrtYd")
		)
		(fp_rect
			(start -0.508 0.9398)
			(end 0.508 -0.9398)
			(stroke
				(width 0)
				(type default)
			)
			(fill no)
			(layer "F.Fab")
		)
		(pad "1" smd custom
			(at 0 -0.4445)
			(size 0.1397 0.1397)
			(layers "F.Cu" "F.Mask" "F.Paste")
			(net "UART_SEL_B_MUX")
			(options
				(clearance outline)
				(anchor circle)
			)
			(primitives
				(gr_poly
					(pts
						(arc
							(start -0.1778 -0.2794)
							(mid -0.249642 -0.249642)
							(end -0.2794 -0.1778)
						)
						(arc
							(start -0.2794 0.1778)
							(mid -0.249642 0.249642)
							(end -0.1778 0.2794)
						)
						(arc
							(start 0.1778 0.2794)
							(mid 0.249642 0.249642)
							(end 0.2794 0.1778)
						)
						(arc
							(start 0.2794 -0.1778)
							(mid 0.249642 -0.249642)
							(end 0.1778 -0.2794)
						)
					)
					(width 0)
					(fill yes)
				)
			)
		)
		(pad "2" smd custom
			(at 0 0.4445)
			(size 0.1397 0.1397)
			(layers "F.Cu" "F.Mask" "F.Paste")
			(net "UART_SEL_B_MUX_R")
			(options
				(clearance outline)
				(anchor circle)
			)
			(primitives
				(gr_poly
					(pts
						(arc
							(start -0.1778 -0.2794)
							(mid -0.249642 -0.249642)
							(end -0.2794 -0.1778)
						)
						(arc
							(start -0.2794 0.1778)
							(mid -0.249642 0.249642)
							(end -0.1778 0.2794)
						)
						(arc
							(start 0.1778 0.2794)
							(mid 0.249642 0.249642)
							(end 0.2794 0.1778)
						)
						(arc
							(start 0.2794 -0.1778)
							(mid 0.249642 -0.249642)
							(end 0.1778 -0.2794)
						)
					)
					(width 0)
					(fill yes)
				)
			)
		)
	)
	(footprint ""
		(layer "F.Cu")
		(at 45.466 -17.8308 90)
		(property "Reference" "R58"
			(at 0 0 90)
			(layer "F.SilkS")
			(hide yes)
			(effects
				(font
					(size 1.27 1.27)
				)
			)
		)
		(property "Value" "20KR2F-L-GP"
			(at 0.064008 -3.993896 90)
			(unlocked yes)
			(layer "F.Fab")
			(hide yes)
			(effects
				(font
					(size 1.016 1.016)
					(thickness 0.1524)
				)
			)
		)
		(property "Device Type" "R402H16"
			(at 0.064008 -5.517896 90)
			(unlocked yes)
			(layer "F.Fab")
			(hide yes)
			(effects
				(font
					(size 1.016 1.016)
					(thickness 0.1524)
				)
			)
		)
		(duplicate_pad_numbers_are_jumpers no)
		(fp_line
			(start 0.508 -0.9398)
			(end -0.508 -0.9398)
			(stroke
				(width 0.1524)
				(type default)
			)
			(layer "F.SilkS")
		)
		(fp_line
			(start -0.508 -0.9398)
			(end -0.508 0.9398)
			(stroke
				(width 0.1524)
				(type default)
			)
			(layer "F.SilkS")
		)
		(fp_rect
			(start -0.508 0.9398)
			(end 0.508 -0.9398)
			(stroke
				(width 0)
				(type default)
			)
			(fill no)
			(layer "F.CrtYd")
		)
		(fp_rect
			(start -0.508 0.9398)
			(end 0.508 -0.9398)
			(stroke
				(width 0)
				(type default)
			)
			(fill no)
			(layer "F.Fab")
		)
		(pad "1" smd custom
			(at 0 -0.4445 90)
			(size 0.1397 0.1397)
			(layers "F.Cu" "F.Mask" "F.Paste")
			(net "P3V3_STBY_B")
			(options
				(clearance outline)
				(anchor circle)
			)
			(primitives
				(gr_poly
					(pts
						(arc
							(start -0.1778 -0.2794)
							(mid -0.249642 -0.249642)
							(end -0.2794 -0.1778)
						)
						(arc
							(start -0.2794 0.1778)
							(mid -0.249642 0.249642)
							(end -0.1778 0.2794)
						)
						(arc
							(start 0.1778 0.2794)
							(mid 0.249642 0.249642)
							(end 0.2794 0.1778)
						)
						(arc
							(start 0.2794 -0.1778)
							(mid 0.249642 -0.249642)
							(end 0.1778 -0.2794)
						)
					)
					(width 0)
					(fill yes)
				)
			)
		)
		(pad "2" smd custom
			(at 0 0.4445 90)
			(size 0.1397 0.1397)
			(layers "F.Cu" "F.Mask" "F.Paste")
			(net "I2C_DEBUG_B_SCL_L")
			(options
				(clearance outline)
				(anchor circle)
			)
			(primitives
				(gr_poly
					(pts
						(arc
							(start -0.1778 -0.2794)
							(mid -0.249642 -0.249642)
							(end -0.2794 -0.1778)
						)
						(arc
							(start -0.2794 0.1778)
							(mid -0.249642 0.249642)
							(end -0.1778 0.2794)
						)
						(arc
							(start 0.1778 0.2794)
							(mid 0.249642 0.249642)
							(end 0.2794 0.1778)
						)
						(arc
							(start 0.2794 -0.1778)
							(mid 0.249642 -0.249642)
							(end 0.1778 -0.2794)
						)
					)
					(width 0)
					(fill yes)
				)
			)
		)
	)
)
